(kicad_pcb
	(version 20260206)
	(generator "pcbnew")
	(generator_version "10.0")
	(general
		(thickness 1.6)
		(legacy_teardrops no)
	)
	(paper "A4")
	(title_block
		(title "peb — Lightning_PEB_BRD.brd")
		(comment 1 "Lightning (Wiwynn / Facebook NVMe JBOF) / footprint 1445 of 2563 (U1), pads 933-1050 of 1311")
	)
	(layers
		(0 "F.Cu" signal "TOP")
		(4 "In1.Cu" signal "L2GND")
		(6 "In2.Cu" signal "L3")
		(8 "In3.Cu" signal "L4VCC")
		(10 "In4.Cu" signal "L5VCC")
		(12 "In5.Cu" signal "L6")
		(14 "In6.Cu" signal "L7GND")
		(2 "B.Cu" signal "BOTTOM")
		(9 "F.Adhes" user "F.Adhesive")
		(11 "B.Adhes" user "B.Adhesive")
		(13 "F.Paste" user "Package Geometry/Pastemask Top")
		(15 "B.Paste" user "Package Geometry/Pastemask Bottom")
		(5 "F.SilkS" user "Ref Des/Silkscreen Top")
		(7 "B.SilkS" user "Ref Des/Silkscreen Bottom")
		(1 "F.Mask" user "Board Geometry/Soldermask Top")
		(3 "B.Mask" user "Board Geometry/Soldermask Bottom")
		(17 "Dwgs.User" user "User.Drawings")
		(19 "Cmts.User" user "User.Comments")
		(21 "Eco1.User" user "User.Eco1")
		(23 "Eco2.User" user "User.Eco2")
		(25 "Edge.Cuts" user "Board Geometry/Outline")
		(27 "Margin" user)
		(31 "F.CrtYd" user "Package Geometry/Place Bound Top")
		(29 "B.CrtYd" user "Package Geometry/Place Bound Bottom")
		(35 "F.Fab" user "Ref Des/Assembly Top")
		(33 "B.Fab" user "Ref Des/Assembly Bottom")
	)
	(footprint ""
		(layer "F.Cu")
		(at 240.599976 -47.999904 -90)
		(property "Reference" "U1"
			(at 0 0 270)
			(layer "F.SilkS")
			(hide yes)
			(effects
				(font
					(size 1.27 1.27)
				)
			)
		)
		(property "Value" "PM8546A-FEIP-GP"
			(at -25.785064 -6.40334 270)
			(unlocked yes)
			(layer "F.Fab")
			(hide yes)
			(effects
				(font
					(size 1.016 1.016)
					(thickness 0.1524)
				)
			)
		)
		(property "Device Type" "BGA1311C37D5H134"
			(at -25.785064 -7.92734 270)
			(unlocked yes)
			(layer "F.Fab")
			(hide yes)
			(effects
				(font
					(size 1.016 1.016)
					(thickness 0.1524)
				)
			)
		)
		(duplicate_pad_numbers_are_jumpers no)
		(pad "K20" smd circle
			(at 0.999998 -8.999982 270)
			(size 0.4572 0.4572)
			(layers "F.Cu" "F.Mask" "F.Paste")
			(net "GND")
		)
		(pad "K21" smd circle
			(at 1.999996 -8.999982 270)
			(size 0.4572 0.4572)
			(layers "F.Cu" "F.Mask" "F.Paste")
			(net "GND")
		)
		(pad "K22" smd circle
			(at 2.999994 -8.999982 270)
			(size 0.4572 0.4572)
			(layers "F.Cu" "F.Mask" "F.Paste")
			(net "GND")
		)
		(pad "K23" smd circle
			(at 3.999992 -8.999982 270)
			(size 0.4572 0.4572)
			(layers "F.Cu" "F.Mask" "F.Paste")
			(net "GND")
		)
		(pad "K24" smd circle
			(at 4.99999 -8.999982 270)
			(size 0.4572 0.4572)
			(layers "F.Cu" "F.Mask" "F.Paste")
			(net "GND")
		)
		(pad "K25" smd circle
			(at 5.999988 -8.999982 270)
			(size 0.4572 0.4572)
			(layers "F.Cu" "F.Mask" "F.Paste")
			(net "GND")
		)
		(pad "K26" smd circle
			(at 6.999986 -8.999982 270)
			(size 0.4572 0.4572)
			(layers "F.Cu" "F.Mask" "F.Paste")
			(net "Net_2105")
		)
		(pad "K27" smd circle
			(at 7.999984 -8.999982 270)
			(size 0.4572 0.4572)
			(layers "F.Cu" "F.Mask" "F.Paste")
			(net "TWI_SCL1")
		)
		(pad "K28" smd circle
			(at 8.999982 -8.999982 270)
			(size 0.4572 0.4572)
			(layers "F.Cu" "F.Mask" "F.Paste")
			(net "TWI_SCL2")
		)
		(pad "K29" smd circle
			(at 9.99998 -8.999982 270)
			(size 0.4572 0.4572)
			(layers "F.Cu" "F.Mask" "F.Paste")
			(net "GND")
		)
		(pad "K30" smd circle
			(at 10.999978 -8.999982 270)
			(size 0.4572 0.4572)
			(layers "F.Cu" "F.Mask" "F.Paste")
			(net "TWI_SDA1")
		)
		(pad "K31" smd circle
			(at 11.999976 -8.999982 270)
			(size 0.4572 0.4572)
			(layers "F.Cu" "F.Mask" "F.Paste")
			(net "TWI_SRST#1")
		)
		(pad "K32" smd circle
			(at 12.999974 -8.999982 270)
			(size 0.4572 0.4572)
			(layers "F.Cu" "F.Mask" "F.Paste")
			(net "GND")
		)
		(pad "K33" smd circle
			(at 13.999972 -8.999982 270)
			(size 0.4572 0.4572)
			(layers "F.Cu" "F.Mask" "F.Paste")
			(net "TWI_SDA2")
		)
		(pad "K34" smd circle
			(at 14.99997 -8.999982 270)
			(size 0.4572 0.4572)
			(layers "F.Cu" "F.Mask" "F.Paste")
			(net "GND")
		)
		(pad "K35" smd circle
			(at 15.999968 -8.999982 270)
			(size 0.4572 0.4572)
			(layers "F.Cu" "F.Mask" "F.Paste")
			(net "PCIE_RX_P7")
		)
		(pad "K36" smd circle
			(at 16.999966 -8.999982 270)
			(size 0.4572 0.4572)
			(layers "F.Cu" "F.Mask" "F.Paste")
			(net "PCIE_RX_N7")
		)
		(pad "L1" smd circle
			(at -17.999964 -7.999984 270)
			(size 0.4572 0.4572)
			(layers "F.Cu" "F.Mask" "F.Paste")
			(net "PCIE_TX_CAP_N40")
		)
		(pad "L2" smd circle
			(at -16.999966 -7.999984 270)
			(size 0.4572 0.4572)
			(layers "F.Cu" "F.Mask" "F.Paste")
			(net "PCIE_TX_CAP_P40")
		)
		(pad "L3" smd circle
			(at -15.999968 -7.999984 270)
			(size 0.4572 0.4572)
			(layers "F.Cu" "F.Mask" "F.Paste")
			(net "GND")
		)
		(pad "L4" smd circle
			(at -14.99997 -7.999984 270)
			(size 0.4572 0.4572)
			(layers "F.Cu" "F.Mask" "F.Paste")
			(net "PCIE_RX_N40")
		)
		(pad "L5" smd circle
			(at -13.999972 -7.999984 270)
			(size 0.4572 0.4572)
			(layers "F.Cu" "F.Mask" "F.Paste")
			(net "PCIE_RX_P40")
		)
		(pad "L6" smd circle
			(at -12.999974 -7.999984 270)
			(size 0.4572 0.4572)
			(layers "F.Cu" "F.Mask" "F.Paste")
			(net "GND")
		)
		(pad "L7" smd circle
			(at -11.999976 -7.999984 270)
			(size 0.4572 0.4572)
			(layers "F.Cu" "F.Mask" "F.Paste")
			(net "DUT_AVD_PCIE")
		)
		(pad "L8" smd circle
			(at -10.999978 -7.999984 270)
			(size 0.4572 0.4572)
			(layers "F.Cu" "F.Mask" "F.Paste")
			(net "GND")
		)
		(pad "L9" smd circle
			(at -9.99998 -7.999984 270)
			(size 0.4572 0.4572)
			(layers "F.Cu" "F.Mask" "F.Paste")
			(net "GND")
		)
		(pad "L10" smd circle
			(at -8.999982 -7.999984 270)
			(size 0.4572 0.4572)
			(layers "F.Cu" "F.Mask" "F.Paste")
			(net "GND")
		)
		(pad "L11" smd circle
			(at -7.999984 -7.999984 270)
			(size 0.4572 0.4572)
			(layers "F.Cu" "F.Mask" "F.Paste")
			(net "GND")
		)
		(pad "L12" smd circle
			(at -6.999986 -7.999984 270)
			(size 0.4572 0.4572)
			(layers "F.Cu" "F.Mask" "F.Paste")
			(net "GND")
		)
		(pad "L13" smd circle
			(at -5.999988 -7.999984 270)
			(size 0.4572 0.4572)
			(layers "F.Cu" "F.Mask" "F.Paste")
			(net "DUT_AVD_PCIE_Q")
		)
		(pad "L14" smd circle
			(at -4.99999 -7.999984 270)
			(size 0.4572 0.4572)
			(layers "F.Cu" "F.Mask" "F.Paste")
			(net "GND")
		)
		(pad "L15" smd circle
			(at -3.999992 -7.999984 270)
			(size 0.4572 0.4572)
			(layers "F.Cu" "F.Mask" "F.Paste")
			(net "GND")
		)
		(pad "L16" smd circle
			(at -2.999994 -7.999984 270)
			(size 0.4572 0.4572)
			(layers "F.Cu" "F.Mask" "F.Paste")
			(net "GND")
		)
		(pad "L17" smd circle
			(at -1.999996 -7.999984 270)
			(size 0.4572 0.4572)
			(layers "F.Cu" "F.Mask" "F.Paste")
			(net "GND")
		)
		(pad "L18" smd circle
			(at -0.999998 -7.999984 270)
			(size 0.4572 0.4572)
			(layers "F.Cu" "F.Mask" "F.Paste")
			(net "GND")
		)
		(pad "L19" smd circle
			(at 0 -7.999984 270)
			(size 0.4572 0.4572)
			(layers "F.Cu" "F.Mask" "F.Paste")
			(net "GND")
		)
		(pad "L20" smd circle
			(at 0.999998 -7.999984 270)
			(size 0.4572 0.4572)
			(layers "F.Cu" "F.Mask" "F.Paste")
			(net "DUT_AVD_PCIE_Q")
		)
		(pad "L21" smd circle
			(at 1.999996 -7.999984 270)
			(size 0.4572 0.4572)
			(layers "F.Cu" "F.Mask" "F.Paste")
			(net "GND")
		)
		(pad "L22" smd circle
			(at 2.999994 -7.999984 270)
			(size 0.4572 0.4572)
			(layers "F.Cu" "F.Mask" "F.Paste")
			(net "DUT_AVD_PCIE")
		)
		(pad "L23" smd circle
			(at 3.999992 -7.999984 270)
			(size 0.4572 0.4572)
			(layers "F.Cu" "F.Mask" "F.Paste")
			(net "GND")
		)
		(pad "L24" smd circle
			(at 4.99999 -7.999984 270)
			(size 0.4572 0.4572)
			(layers "F.Cu" "F.Mask" "F.Paste")
			(net "GND")
		)
		(pad "L25" smd circle
			(at 5.999988 -7.999984 270)
			(size 0.4572 0.4572)
			(layers "F.Cu" "F.Mask" "F.Paste")
			(net "GND")
		)
		(pad "L26" smd circle
			(at 6.999986 -7.999984 270)
			(size 0.4572 0.4572)
			(layers "F.Cu" "F.Mask" "F.Paste")
			(net "GPIO107_R")
		)
		(pad "L27" smd circle
			(at 7.999984 -7.999984 270)
			(size 0.4572 0.4572)
			(layers "F.Cu" "F.Mask" "F.Paste")
			(net "GPIO108_R")
		)
		(pad "L28" smd circle
			(at 8.999982 -7.999984 270)
			(size 0.4572 0.4572)
			(layers "F.Cu" "F.Mask" "F.Paste")
			(net "TWI_SRST#2")
		)
		(pad "L29" smd circle
			(at 9.99998 -7.999984 270)
			(size 0.4572 0.4572)
			(layers "F.Cu" "F.Mask" "F.Paste")
			(net "TWI_SDA5")
		)
		(pad "L30" smd circle
			(at 10.999978 -7.999984 270)
			(size 0.4572 0.4572)
			(layers "F.Cu" "F.Mask" "F.Paste")
			(net "TWI_SCL5")
		)
		(pad "L31" smd circle
			(at 11.999976 -7.999984 270)
			(size 0.4572 0.4572)
			(layers "F.Cu" "F.Mask" "F.Paste")
			(net "DUT_VDDO")
		)
		(pad "L32" smd circle
			(at 12.999974 -7.999984 270)
			(size 0.4572 0.4572)
			(layers "F.Cu" "F.Mask" "F.Paste")
			(net "GPIO109_R")
		)
		(pad "L33" smd circle
			(at 13.999972 -7.999984 270)
			(size 0.4572 0.4572)
			(layers "F.Cu" "F.Mask" "F.Paste")
			(net "IOEXP_INT#_3")
		)
		(pad "L34" smd circle
			(at 14.99997 -7.999984 270)
			(size 0.4572 0.4572)
			(layers "F.Cu" "F.Mask" "F.Paste")
			(net "DUT_VDDO")
		)
		(pad "L35" smd circle
			(at 15.999968 -7.999984 270)
			(size 0.4572 0.4572)
			(layers "F.Cu" "F.Mask" "F.Paste")
			(net "GND")
		)
		(pad "L36" smd circle
			(at 16.999966 -7.999984 270)
			(size 0.4572 0.4572)
			(layers "F.Cu" "F.Mask" "F.Paste")
			(net "PCIE_RX_P6")
		)
		(pad "L37" smd circle
			(at 17.999964 -7.999984 270)
			(size 0.4572 0.4572)
			(layers "F.Cu" "F.Mask" "F.Paste")
			(net "PCIE_RX_N6")
		)
		(pad "M2" smd circle
			(at -16.999966 -6.999986 270)
			(size 0.4572 0.4572)
			(layers "F.Cu" "F.Mask" "F.Paste")
			(net "PCIE_TX_CAP_N41")
		)
		(pad "M3" smd circle
			(at -15.999968 -6.999986 270)
			(size 0.4572 0.4572)
			(layers "F.Cu" "F.Mask" "F.Paste")
			(net "PCIE_TX_CAP_P41")
		)
		(pad "M4" smd circle
			(at -14.99997 -6.999986 270)
			(size 0.4572 0.4572)
			(layers "F.Cu" "F.Mask" "F.Paste")
			(net "GND")
		)
		(pad "M5" smd circle
			(at -13.999972 -6.999986 270)
			(size 0.4572 0.4572)
			(layers "F.Cu" "F.Mask" "F.Paste")
			(net "PCIE_RX_N41")
		)
		(pad "M6" smd circle
			(at -12.999974 -6.999986 270)
			(size 0.4572 0.4572)
			(layers "F.Cu" "F.Mask" "F.Paste")
			(net "PCIE_RX_P41")
		)
		(pad "M7" smd circle
			(at -11.999976 -6.999986 270)
			(size 0.4572 0.4572)
			(layers "F.Cu" "F.Mask" "F.Paste")
			(net "DUT_AVD_PCIE")
		)
		(pad "M8" smd circle
			(at -10.999978 -6.999986 270)
			(size 0.4572 0.4572)
			(layers "F.Cu" "F.Mask" "F.Paste")
			(net "GND")
		)
		(pad "M9" smd circle
			(at -9.99998 -6.999986 270)
			(size 0.4572 0.4572)
			(layers "F.Cu" "F.Mask" "F.Paste")
			(net "GND")
		)
		(pad "M10" smd circle
			(at -8.999982 -6.999986 270)
			(size 0.4572 0.4572)
			(layers "F.Cu" "F.Mask" "F.Paste")
			(net "GND")
		)
		(pad "M11" smd circle
			(at -7.999984 -6.999986 270)
			(size 0.4572 0.4572)
			(layers "F.Cu" "F.Mask" "F.Paste")
			(net "GND")
		)
		(pad "M12" smd circle
			(at -6.999986 -6.999986 270)
			(size 0.4572 0.4572)
			(layers "F.Cu" "F.Mask" "F.Paste")
			(net "GND")
		)
		(pad "M13" smd circle
			(at -5.999988 -6.999986 270)
			(size 0.4572 0.4572)
			(layers "F.Cu" "F.Mask" "F.Paste")
			(net "DUT_AVD_PCIE")
		)
		(pad "M14" smd circle
			(at -4.99999 -6.999986 270)
			(size 0.4572 0.4572)
			(layers "F.Cu" "F.Mask" "F.Paste")
			(net "GND")
		)
		(pad "M15" smd circle
			(at -3.999992 -6.999986 270)
			(size 0.4572 0.4572)
			(layers "F.Cu" "F.Mask" "F.Paste")
			(net "DUT_VDD")
		)
		(pad "M16" smd circle
			(at -2.999994 -6.999986 270)
			(size 0.4572 0.4572)
			(layers "F.Cu" "F.Mask" "F.Paste")
			(net "GND")
		)
		(pad "M17" smd circle
			(at -1.999996 -6.999986 270)
			(size 0.4572 0.4572)
			(layers "F.Cu" "F.Mask" "F.Paste")
			(net "DUT_VDD")
		)
		(pad "M18" smd circle
			(at -0.999998 -6.999986 270)
			(size 0.4572 0.4572)
			(layers "F.Cu" "F.Mask" "F.Paste")
			(net "GND")
		)
		(pad "M19" smd circle
			(at 0 -6.999986 270)
			(size 0.4572 0.4572)
			(layers "F.Cu" "F.Mask" "F.Paste")
			(net "DUT_VDD")
		)
		(pad "M20" smd circle
			(at 0.999998 -6.999986 270)
			(size 0.4572 0.4572)
			(layers "F.Cu" "F.Mask" "F.Paste")
			(net "GND")
		)
		(pad "M21" smd circle
			(at 1.999996 -6.999986 270)
			(size 0.4572 0.4572)
			(layers "F.Cu" "F.Mask" "F.Paste")
			(net "DUT_AVD_PCIE")
		)
		(pad "M22" smd circle
			(at 2.999994 -6.999986 270)
			(size 0.4572 0.4572)
			(layers "F.Cu" "F.Mask" "F.Paste")
			(net "GND")
		)
		(pad "M23" smd circle
			(at 3.999992 -6.999986 270)
			(size 0.4572 0.4572)
			(layers "F.Cu" "F.Mask" "F.Paste")
			(net "DUT_VDD")
		)
		(pad "M24" smd circle
			(at 4.99999 -6.999986 270)
			(size 0.4572 0.4572)
			(layers "F.Cu" "F.Mask" "F.Paste")
			(net "GND")
		)
		(pad "M25" smd circle
			(at 5.999988 -6.999986 270)
			(size 0.4572 0.4572)
			(layers "F.Cu" "F.Mask" "F.Paste")
			(net "DUT_VDD")
		)
		(pad "M26" smd circle
			(at 6.999986 -6.999986 270)
			(size 0.4572 0.4572)
			(layers "F.Cu" "F.Mask" "F.Paste")
			(net "TWI_SRST#5")
		)
		(pad "M27" smd circle
			(at 7.999984 -6.999986 270)
			(size 0.4572 0.4572)
			(layers "F.Cu" "F.Mask" "F.Paste")
			(net "TWI_SCL6")
		)
		(pad "M28" smd circle
			(at 8.999982 -6.999986 270)
			(size 0.4572 0.4572)
			(layers "F.Cu" "F.Mask" "F.Paste")
			(net "IOEXP_INT#_4")
		)
		(pad "M29" smd circle
			(at 9.99998 -6.999986 270)
			(size 0.4572 0.4572)
			(layers "F.Cu" "F.Mask" "F.Paste")
			(net "IOEXP_PMC1_INT#")
		)
		(pad "M30" smd circle
			(at 10.999978 -6.999986 270)
			(size 0.4572 0.4572)
			(layers "F.Cu" "F.Mask" "F.Paste")
			(net "TWI_SRST#8")
		)
		(pad "M31" smd circle
			(at 11.999976 -6.999986 270)
			(size 0.4572 0.4572)
			(layers "F.Cu" "F.Mask" "F.Paste")
			(net "TWI_SDA6")
		)
		(pad "M32" smd circle
			(at 12.999974 -6.999986 270)
			(size 0.4572 0.4572)
			(layers "F.Cu" "F.Mask" "F.Paste")
			(net "TWI_SRST#6")
		)
		(pad "M33" smd circle
			(at 13.999972 -6.999986 270)
			(size 0.4572 0.4572)
			(layers "F.Cu" "F.Mask" "F.Paste")
			(net "TWI_SDA9")
		)
		(pad "M34" smd circle
			(at 14.99997 -6.999986 270)
			(size 0.4572 0.4572)
			(layers "F.Cu" "F.Mask" "F.Paste")
			(net "GND")
		)
		(pad "M35" smd circle
			(at 15.999968 -6.999986 270)
			(size 0.4572 0.4572)
			(layers "F.Cu" "F.Mask" "F.Paste")
			(net "PCIE_RX_P5")
		)
		(pad "M36" smd circle
			(at 16.999966 -6.999986 270)
			(size 0.4572 0.4572)
			(layers "F.Cu" "F.Mask" "F.Paste")
			(net "PCIE_RX_N5")
		)
		(pad "N1" smd circle
			(at -17.999964 -5.999988 270)
			(size 0.4572 0.4572)
			(layers "F.Cu" "F.Mask" "F.Paste")
			(net "PCIE_TX_CAP_N42")
		)
		(pad "N2" smd circle
			(at -16.999966 -5.999988 270)
			(size 0.4572 0.4572)
			(layers "F.Cu" "F.Mask" "F.Paste")
			(net "PCIE_TX_CAP_P42")
		)
		(pad "N3" smd circle
			(at -15.999968 -5.999988 270)
			(size 0.4572 0.4572)
			(layers "F.Cu" "F.Mask" "F.Paste")
			(net "GND")
		)
		(pad "N4" smd circle
			(at -14.99997 -5.999988 270)
			(size 0.4572 0.4572)
			(layers "F.Cu" "F.Mask" "F.Paste")
			(net "PCIE_RX_N42")
		)
		(pad "N5" smd circle
			(at -13.999972 -5.999988 270)
			(size 0.4572 0.4572)
			(layers "F.Cu" "F.Mask" "F.Paste")
			(net "PCIE_RX_P42")
		)
		(pad "N6" smd circle
			(at -12.999974 -5.999988 270)
			(size 0.4572 0.4572)
			(layers "F.Cu" "F.Mask" "F.Paste")
			(net "GND")
		)
		(pad "N7" smd circle
			(at -11.999976 -5.999988 270)
			(size 0.4572 0.4572)
			(layers "F.Cu" "F.Mask" "F.Paste")
			(net "DUT_AVD_PCIE")
		)
		(pad "N8" smd circle
			(at -10.999978 -5.999988 270)
			(size 0.4572 0.4572)
			(layers "F.Cu" "F.Mask" "F.Paste")
			(net "GND")
		)
		(pad "N9" smd circle
			(at -9.99998 -5.999988 270)
			(size 0.4572 0.4572)
			(layers "F.Cu" "F.Mask" "F.Paste")
			(net "GND")
		)
		(pad "N10" smd circle
			(at -8.999982 -5.999988 270)
			(size 0.4572 0.4572)
			(layers "F.Cu" "F.Mask" "F.Paste")
			(net "GND")
		)
		(pad "N11" smd circle
			(at -7.999984 -5.999988 270)
			(size 0.4572 0.4572)
			(layers "F.Cu" "F.Mask" "F.Paste")
			(net "GND")
		)
		(pad "N12" smd circle
			(at -6.999986 -5.999988 270)
			(size 0.4572 0.4572)
			(layers "F.Cu" "F.Mask" "F.Paste")
			(net "GND")
		)
		(pad "N13" smd circle
			(at -5.999988 -5.999988 270)
			(size 0.4572 0.4572)
			(layers "F.Cu" "F.Mask" "F.Paste")
			(net "GND")
		)
		(pad "N14" smd circle
			(at -4.99999 -5.999988 270)
			(size 0.4572 0.4572)
			(layers "F.Cu" "F.Mask" "F.Paste")
			(net "DUT_VDD")
		)
		(pad "N15" smd circle
			(at -3.999992 -5.999988 270)
			(size 0.4572 0.4572)
			(layers "F.Cu" "F.Mask" "F.Paste")
			(net "GND")
		)
		(pad "N16" smd circle
			(at -2.999994 -5.999988 270)
			(size 0.4572 0.4572)
			(layers "F.Cu" "F.Mask" "F.Paste")
			(net "DUT_VDD")
		)
		(pad "N17" smd circle
			(at -1.999996 -5.999988 270)
			(size 0.4572 0.4572)
			(layers "F.Cu" "F.Mask" "F.Paste")
			(net "GND")
		)
		(pad "N18" smd circle
			(at -0.999998 -5.999988 270)
			(size 0.4572 0.4572)
			(layers "F.Cu" "F.Mask" "F.Paste")
			(net "DUT_VDD")
		)
		(pad "N19" smd circle
			(at 0 -5.999988 270)
			(size 0.4572 0.4572)
			(layers "F.Cu" "F.Mask" "F.Paste")
			(net "GND")
		)
		(pad "N20" smd circle
			(at 0.999998 -5.999988 270)
			(size 0.4572 0.4572)
			(layers "F.Cu" "F.Mask" "F.Paste")
			(net "DUT_VDD")
		)
		(pad "N21" smd circle
			(at 1.999996 -5.999988 270)
			(size 0.4572 0.4572)
			(layers "F.Cu" "F.Mask" "F.Paste")
			(net "GND")
		)
		(pad "N22" smd circle
			(at 2.999994 -5.999988 270)
			(size 0.4572 0.4572)
			(layers "F.Cu" "F.Mask" "F.Paste")
			(net "DUT_VDD")
		)
		(pad "N23" smd circle
			(at 3.999992 -5.999988 270)
			(size 0.4572 0.4572)
			(layers "F.Cu" "F.Mask" "F.Paste")
			(net "GND")
		)
		(pad "N24" smd circle
			(at 4.99999 -5.999988 270)
			(size 0.4572 0.4572)
			(layers "F.Cu" "F.Mask" "F.Paste")
			(net "DUT_VDD")
		)
		(pad "N25" smd circle
			(at 5.999988 -5.999988 270)
			(size 0.4572 0.4572)
			(layers "F.Cu" "F.Mask" "F.Paste")
			(net "GND")
		)
		(pad "N26" smd circle
			(at 6.999986 -5.999988 270)
			(size 0.4572 0.4572)
			(layers "F.Cu" "F.Mask" "F.Paste")
			(net "DUT_VDDO_REF")
		)
		(pad "N27" smd circle
			(at 7.999984 -5.999988 270)
			(size 0.4572 0.4572)
			(layers "F.Cu" "F.Mask" "F.Paste")
			(net "TWI_SRST#9")
		)
		(pad "N28" smd circle
			(at 8.999982 -5.999988 270)
			(size 0.4572 0.4572)
			(layers "F.Cu" "F.Mask" "F.Paste")
			(net "IOEXP_INT#_1")
		)
		(pad "N29" smd circle
			(at 9.99998 -5.999988 270)
			(size 0.4572 0.4572)
			(layers "F.Cu" "F.Mask" "F.Paste")
			(net "GND")
		)
	)
)
